(kicad_pcb
	(version 20260206)
	(generator "pcbnew")
	(generator_version "10.0")
	(general
		(thickness 1.6)
		(legacy_teardrops no)
	)
	(paper "A4")
	(title_block
		(title "03242023_DA0F0TMBIJ0_F0T_Motherboard_J_brd_V01_OCP.brd")
		(comment 1 "Grand Teton / footprints 1497-1501 of 6105")
	)
	(layers
		(0 "F.Cu" signal "TOP")
		(4 "In1.Cu" signal "GND")
		(6 "In2.Cu" signal "IN1")
		(8 "In3.Cu" signal "GND1")
		(10 "In4.Cu" signal "IN2")
		(12 "In5.Cu" signal "GND2")
		(14 "In6.Cu" signal "IN3")
		(16 "In7.Cu" signal "GND3")
		(18 "In8.Cu" signal "VCC")
		(20 "In9.Cu" signal "VCC1")
		(22 "In10.Cu" signal "GND4")
		(24 "In11.Cu" signal "IN4")
		(26 "In12.Cu" signal "GND5")
		(28 "In13.Cu" signal "IN5")
		(30 "In14.Cu" signal "GND6")
		(32 "In15.Cu" signal "IN6")
		(34 "In16.Cu" signal "GND7")
		(2 "B.Cu" signal "BOTTOM")
		(9 "F.Adhes" user "F.Adhesive")
		(11 "B.Adhes" user "B.Adhesive")
		(13 "F.Paste" user "Package Geometry/Pastemask Top")
		(15 "B.Paste" user "Package Geometry/Pastemask Bottom")
		(5 "F.SilkS" user "Ref Des/Silkscreen Top")
		(7 "B.SilkS" user "Ref Des/Silkscreen Bottom")
		(1 "F.Mask" user "Board Geometry/Soldermask Top")
		(3 "B.Mask" user "Board Geometry/Soldermask Bottom")
		(17 "Dwgs.User" user "User.Drawings")
		(19 "Cmts.User" user "User.Comments")
		(21 "Eco1.User" user "User.Eco1")
		(23 "Eco2.User" user "User.Eco2")
		(25 "Edge.Cuts" user "Board Geometry/Outline")
		(27 "Margin" user)
		(31 "F.CrtYd" user "Package Geometry/Place Bound Top")
		(29 "B.CrtYd" user "Package Geometry/Place Bound Bottom")
		(35 "F.Fab" user "Ref Des/Assembly Top")
		(33 "B.Fab" user "Ref Des/Assembly Bottom")
	)
	(footprint ""
		(layer "F.Cu")
		(at 244.596666 -394.17117)
		(property "Reference" "PR2535"
			(at 0 0 0)
			(layer "F.SilkS")
			(hide yes)
			(effects
				(font
					(size 1.27 1.27)
				)
			)
		)
		(property "Value" ""
			(at 0 0 0)
			(layer "F.Fab")
			(effects
				(font
					(size 1.27 1.27)
				)
			)
		)
		(duplicate_pad_numbers_are_jumpers no)
		(fp_line
			(start -0.7874 -0.4064)
			(end 0.7874 -0.4064)
			(stroke
				(width 0.1524)
				(type default)
			)
			(layer "F.SilkS")
		)
		(fp_line
			(start -0.7874 0.4064)
			(end -0.7874 -0.4064)
			(stroke
				(width 0.1524)
				(type default)
			)
			(layer "F.SilkS")
		)
		(fp_line
			(start 0.7874 -0.4064)
			(end 0.7874 0.4064)
			(stroke
				(width 0.1524)
				(type default)
			)
			(layer "F.SilkS")
		)
		(fp_line
			(start 0.7874 0.4064)
			(end -0.7874 0.4064)
			(stroke
				(width 0.1524)
				(type default)
			)
			(layer "F.SilkS")
		)
		(fp_line
			(start -0.67945 -0.305054)
			(end -0.12065 -0.305054)
			(stroke
				(width 0.1)
				(type default)
			)
			(layer "F.Fab")
		)
		(fp_line
			(start -0.67945 0.3048)
			(end -0.67945 -0.305054)
			(stroke
				(width 0.1)
				(type default)
			)
			(layer "F.Fab")
		)
		(fp_line
			(start -0.12065 -0.305054)
			(end -0.12065 -0.2794)
			(stroke
				(width 0.1)
				(type default)
			)
			(layer "F.Fab")
		)
		(fp_line
			(start -0.12065 -0.2794)
			(end 0.12065 -0.2794)
			(stroke
				(width 0.1)
				(type default)
			)
			(layer "F.Fab")
		)
		(fp_line
			(start -0.12065 0.2794)
			(end -0.12065 0.3048)
			(stroke
				(width 0.1)
				(type default)
			)
			(layer "F.Fab")
		)
		(fp_line
			(start -0.12065 0.3048)
			(end -0.67945 0.3048)
			(stroke
				(width 0.1)
				(type default)
			)
			(layer "F.Fab")
		)
		(fp_line
			(start 0.120396 0.2794)
			(end -0.12065 0.2794)
			(stroke
				(width 0.1)
				(type default)
			)
			(layer "F.Fab")
		)
		(fp_line
			(start 0.120396 0.3048)
			(end 0.120396 0.2794)
			(stroke
				(width 0.1)
				(type default)
			)
			(layer "F.Fab")
		)
		(fp_line
			(start 0.12065 -0.3048)
			(end 0.67945 -0.3048)
			(stroke
				(width 0.1)
				(type default)
			)
			(layer "F.Fab")
		)
		(fp_line
			(start 0.12065 -0.2794)
			(end 0.12065 -0.3048)
			(stroke
				(width 0.1)
				(type default)
			)
			(layer "F.Fab")
		)
		(fp_line
			(start 0.67945 -0.3048)
			(end 0.67945 0.3048)
			(stroke
				(width 0.1)
				(type default)
			)
			(layer "F.Fab")
		)
		(fp_line
			(start 0.67945 0.3048)
			(end 0.120396 0.3048)
			(stroke
				(width 0.1)
				(type default)
			)
			(layer "F.Fab")
		)
		(pad "1" smd circle
			(at -0.40005 0)
			(size 0 0)
			(layers "F.Cu" "F.Mask" "F.Paste")
			(net "P12V_HSC_GATE_G5")
		)
		(pad "2" smd circle
			(at 0.40005 0)
			(size 0 0)
			(layers "F.Cu" "F.Mask" "F.Paste")
			(net "P12V_HSC_GATE2")
		)
	)
	(footprint ""
		(layer "F.Cu")
		(at 331.029056 -19.37766 90)
		(property "Reference" "R1254"
			(at 0 0 90)
			(layer "F.SilkS")
			(hide yes)
			(effects
				(font
					(size 1.27 1.27)
				)
			)
		)
		(property "Value" ""
			(at 0 0 90)
			(layer "F.Fab")
			(effects
				(font
					(size 1.27 1.27)
				)
			)
		)
		(duplicate_pad_numbers_are_jumpers no)
		(fp_line
			(start 0.7874 -0.4064)
			(end 0.7874 0.4064)
			(stroke
				(width 0.1524)
				(type default)
			)
			(layer "F.SilkS")
		)
		(fp_line
			(start -0.7874 -0.4064)
			(end 0.7874 -0.4064)
			(stroke
				(width 0.1524)
				(type default)
			)
			(layer "F.SilkS")
		)
		(fp_line
			(start 0.7874 0.4064)
			(end -0.7874 0.4064)
			(stroke
				(width 0.1524)
				(type default)
			)
			(layer "F.SilkS")
		)
		(fp_line
			(start -0.7874 0.4064)
			(end -0.7874 -0.4064)
			(stroke
				(width 0.1524)
				(type default)
			)
			(layer "F.SilkS")
		)
		(fp_line
			(start -0.12065 -0.305054)
			(end -0.12065 -0.2794)
			(stroke
				(width 0.1)
				(type default)
			)
			(layer "F.Fab")
		)
		(fp_line
			(start -0.67945 -0.305054)
			(end -0.12065 -0.305054)
			(stroke
				(width 0.1)
				(type default)
			)
			(layer "F.Fab")
		)
		(fp_line
			(start 0.67945 -0.3048)
			(end 0.67945 0.3048)
			(stroke
				(width 0.1)
				(type default)
			)
			(layer "F.Fab")
		)
		(fp_line
			(start 0.12065 -0.3048)
			(end 0.67945 -0.3048)
			(stroke
				(width 0.1)
				(type default)
			)
			(layer "F.Fab")
		)
		(fp_line
			(start 0.12065 -0.2794)
			(end 0.12065 -0.3048)
			(stroke
				(width 0.1)
				(type default)
			)
			(layer "F.Fab")
		)
		(fp_line
			(start -0.12065 -0.2794)
			(end 0.12065 -0.2794)
			(stroke
				(width 0.1)
				(type default)
			)
			(layer "F.Fab")
		)
		(fp_line
			(start 0.120396 0.2794)
			(end -0.12065 0.2794)
			(stroke
				(width 0.1)
				(type default)
			)
			(layer "F.Fab")
		)
		(fp_line
			(start -0.12065 0.2794)
			(end -0.12065 0.3048)
			(stroke
				(width 0.1)
				(type default)
			)
			(layer "F.Fab")
		)
		(fp_line
			(start 0.67945 0.3048)
			(end 0.120396 0.3048)
			(stroke
				(width 0.1)
				(type default)
			)
			(layer "F.Fab")
		)
		(fp_line
			(start 0.120396 0.3048)
			(end 0.120396 0.2794)
			(stroke
				(width 0.1)
				(type default)
			)
			(layer "F.Fab")
		)
		(fp_line
			(start -0.12065 0.3048)
			(end -0.67945 0.3048)
			(stroke
				(width 0.1)
				(type default)
			)
			(layer "F.Fab")
		)
		(fp_line
			(start -0.67945 0.3048)
			(end -0.67945 -0.305054)
			(stroke
				(width 0.1)
				(type default)
			)
			(layer "F.Fab")
		)
		(pad "1" smd circle
			(at -0.40005 0 90)
			(size 0 0)
			(layers "F.Cu" "F.Mask" "F.Paste")
			(net "PGPPA_AUX")
		)
		(pad "2" smd circle
			(at 0.40005 0 90)
			(size 0 0)
			(layers "F.Cu" "F.Mask" "F.Paste")
			(net "IRQ_LPC_SERIRQ_ESPI_CS1_N")
		)
	)
	(footprint ""
		(layer "F.Cu")
		(at 490.57433 2.370328 -90)
		(property "Reference" "X16"
			(at -1.342644 2.821178 90)
			(unlocked yes)
			(layer "F.SilkS")
			(effects
				(font
					(size 0.7874 0.5842)
					(thickness 0.1524)
				)
				(justify left)
			)
		)
		(property "Value" ""
			(at 0 0 270)
			(layer "F.Fab")
			(effects
				(font
					(size 1.27 1.27)
				)
			)
		)
		(property "Device Type" "TP_TDR_4P_FTS_TH-TP_TDR_4P_DIPA"
			(at 1.30175 1.27 0)
			(unlocked yes)
			(layer "F.Fab")
			(hide yes)
			(effects
				(font
					(size 0.635 0.4064)
					(thickness 0.1524)
				)
			)
		)
		(property "User Part Number" "N_A"
			(at 1.30175 1.27 0)
			(unlocked yes)
			(layer "Cmts.User")
			(hide yes)
			(effects
				(font
					(size 0.635 0.4064)
					(thickness 0.1524)
				)
			)
		)
		(duplicate_pad_numbers_are_jumpers no)
		(fp_line
			(start 0 3.81)
			(end 2.54 3.81)
			(stroke
				(width 0.1524)
				(type default)
			)
			(layer "F.SilkS")
		)
		(fp_line
			(start 2.54 3.81)
			(end 2.54 3.6703)
			(stroke
				(width 0.1524)
				(type default)
			)
			(layer "F.SilkS")
		)
		(fp_line
			(start 0 3.175)
			(end 0 3.81)
			(stroke
				(width 0.1524)
				(type default)
			)
			(layer "F.SilkS")
		)
		(fp_line
			(start 2.54 1.4097)
			(end 2.54 1.1303)
			(stroke
				(width 0.1524)
				(type default)
			)
			(layer "F.SilkS")
		)
		(fp_line
			(start 0 0.635)
			(end 0 1.905)
			(stroke
				(width 0.1524)
				(type default)
			)
			(layer "F.SilkS")
		)
		(fp_line
			(start 2.54 -1.1303)
			(end 2.54 -1.27)
			(stroke
				(width 0.1524)
				(type default)
			)
			(layer "F.SilkS")
		)
		(fp_line
			(start 0 -1.27)
			(end 0 -0.635)
			(stroke
				(width 0.1524)
				(type default)
			)
			(layer "F.SilkS")
		)
		(fp_line
			(start 2.54 -1.27)
			(end 0 -1.27)
			(stroke
				(width 0.1524)
				(type default)
			)
			(layer "F.SilkS")
		)
		(fp_poly
			(pts
				(xy -1.247648 0.03175) (xy -2.771648 0.79375) (xy -2.771648 -0.73025)
			)
			(stroke
				(width 0)
				(type default)
			)
			(fill yes)
			(layer "F.SilkS")
		)
		(fp_line
			(start 0 3.81)
			(end 2.54 3.81)
			(stroke
				(width 0.1)
				(type default)
			)
			(layer "F.Fab")
		)
		(fp_line
			(start 2.54 3.81)
			(end 2.54 -1.27)
			(stroke
				(width 0.1)
				(type default)
			)
			(layer "F.Fab")
		)
		(fp_line
			(start 0 -1.27)
			(end 0 3.81)
			(stroke
				(width 0.1)
				(type default)
			)
			(layer "F.Fab")
		)
		(fp_line
			(start 2.54 -1.27)
			(end 0 -1.27)
			(stroke
				(width 0.1)
				(type default)
			)
			(layer "F.Fab")
		)
		(fp_poly
			(pts
				(xy -0.761746 0) (xy -2.285746 -0.762) (xy -2.285746 0.762)
			)
			(stroke
				(width 0)
				(type default)
			)
			(fill yes)
			(layer "F.Fab")
		)
		(pad "1" thru_hole circle
			(at 0 0 270)
			(size 1.0033 1.0033)
			(drill 0.249936)
			(layers "*.Cu" "*.Mask")
			(remove_unused_layers no)
			(net "TDR_DIFF_100_IN3_DP")
			(clearance 0.10795)
			(thermal_gap 0.10795)
			(padstack
				(mode front_inner_back)
				(layer "Inner"
					(shape circle)
					(size 0.8001 0.8001)
					(clearance 0.1524)
				)
				(layer "B.Cu"
					(shape circle)
					(size 1.0033 1.0033)
					(clearance 0.10795)
				)
			)
		)
		(pad "2" thru_hole circle
			(at 2.54 0 270)
			(size 1.9939 1.9939)
			(drill 0.249936)
			(layers "*.Cu" "*.Mask")
			(remove_unused_layers no)
			(net "T1_GND")
			(clearance 0.10795)
			(thermal_gap 0.10795)
			(padstack
				(mode front_inner_back)
				(layer "Inner"
					(shape circle)
					(size 0.8001 0.8001)
					(clearance 0.1524)
				)
				(layer "B.Cu"
					(shape circle)
					(size 1.9939 1.9939)
					(clearance 0.10795)
				)
			)
		)
		(pad "3" thru_hole circle
			(at 2.54 2.54 270)
			(size 1.9939 1.9939)
			(drill 0.249936)
			(layers "*.Cu" "*.Mask")
			(remove_unused_layers no)
			(net "T1_GND")
			(clearance 0.10795)
			(thermal_gap 0.10795)
			(padstack
				(mode front_inner_back)
				(layer "Inner"
					(shape circle)
					(size 0.8001 0.8001)
					(clearance 0.1524)
				)
				(layer "B.Cu"
					(shape circle)
					(size 1.9939 1.9939)
					(clearance 0.10795)
				)
			)
		)
		(pad "4" thru_hole circle
			(at 0 2.54 270)
			(size 1.0033 1.0033)
			(drill 0.249936)
			(layers "*.Cu" "*.Mask")
			(remove_unused_layers no)
			(net "TDR_DIFF_100_IN3_DN")
			(clearance 0.10795)
			(thermal_gap 0.10795)
			(padstack
				(mode front_inner_back)
				(layer "Inner"
					(shape circle)
					(size 0.8001 0.8001)
					(clearance 0.1524)
				)
				(layer "B.Cu"
					(shape circle)
					(size 1.0033 1.0033)
					(clearance 0.10795)
				)
			)
		)
	)
	(footprint ""
		(layer "F.Cu")
		(at 73.475596 -74.901552 -90)
		(property "Reference" "R3088"
			(at 0 0 270)
			(layer "F.SilkS")
			(hide yes)
			(effects
				(font
					(size 1.27 1.27)
				)
			)
		)
		(property "Value" ""
			(at 0 0 270)
			(layer "F.Fab")
			(effects
				(font
					(size 1.27 1.27)
				)
			)
		)
		(duplicate_pad_numbers_are_jumpers no)
		(fp_line
			(start -0.7874 0.4064)
			(end -0.7874 -0.4064)
			(stroke
				(width 0.1524)
				(type default)
			)
			(layer "F.SilkS")
		)
		(fp_line
			(start 0.7874 0.4064)
			(end -0.7874 0.4064)
			(stroke
				(width 0.1524)
				(type default)
			)
			(layer "F.SilkS")
		)
		(fp_line
			(start -0.7874 -0.4064)
			(end 0.7874 -0.4064)
			(stroke
				(width 0.1524)
				(type default)
			)
			(layer "F.SilkS")
		)
		(fp_line
			(start 0.7874 -0.4064)
			(end 0.7874 0.4064)
			(stroke
				(width 0.1524)
				(type default)
			)
			(layer "F.SilkS")
		)
		(fp_line
			(start -0.67945 0.3048)
			(end -0.67945 -0.305054)
			(stroke
				(width 0.1)
				(type default)
			)
			(layer "F.Fab")
		)
		(fp_line
			(start -0.12065 0.3048)
			(end -0.67945 0.3048)
			(stroke
				(width 0.1)
				(type default)
			)
			(layer "F.Fab")
		)
		(fp_line
			(start 0.120396 0.3048)
			(end 0.120396 0.2794)
			(stroke
				(width 0.1)
				(type default)
			)
			(layer "F.Fab")
		)
		(fp_line
			(start 0.67945 0.3048)
			(end 0.120396 0.3048)
			(stroke
				(width 0.1)
				(type default)
			)
			(layer "F.Fab")
		)
		(fp_line
			(start -0.12065 0.2794)
			(end -0.12065 0.3048)
			(stroke
				(width 0.1)
				(type default)
			)
			(layer "F.Fab")
		)
		(fp_line
			(start 0.120396 0.2794)
			(end -0.12065 0.2794)
			(stroke
				(width 0.1)
				(type default)
			)
			(layer "F.Fab")
		)
		(fp_line
			(start -0.12065 -0.2794)
			(end 0.12065 -0.2794)
			(stroke
				(width 0.1)
				(type default)
			)
			(layer "F.Fab")
		)
		(fp_line
			(start 0.12065 -0.2794)
			(end 0.12065 -0.3048)
			(stroke
				(width 0.1)
				(type default)
			)
			(layer "F.Fab")
		)
		(fp_line
			(start 0.12065 -0.3048)
			(end 0.67945 -0.3048)
			(stroke
				(width 0.1)
				(type default)
			)
			(layer "F.Fab")
		)
		(fp_line
			(start 0.67945 -0.3048)
			(end 0.67945 0.3048)
			(stroke
				(width 0.1)
				(type default)
			)
			(layer "F.Fab")
		)
		(fp_line
			(start -0.67945 -0.305054)
			(end -0.12065 -0.305054)
			(stroke
				(width 0.1)
				(type default)
			)
			(layer "F.Fab")
		)
		(fp_line
			(start -0.12065 -0.305054)
			(end -0.12065 -0.2794)
			(stroke
				(width 0.1)
				(type default)
			)
			(layer "F.Fab")
		)
		(pad "1" smd circle
			(at -0.40005 0 270)
			(size 0 0)
			(layers "F.Cu" "F.Mask" "F.Paste")
			(net "LED_PWRGD_PVCCFA_EHV_FIVRA_CPU0")
		)
		(pad "2" smd circle
			(at 0.40005 0 270)
			(size 0 0)
			(layers "F.Cu" "F.Mask" "F.Paste")
			(net "P3V3_AUX")
		)
	)
	(footprint ""
		(layer "F.Cu")
		(at 51.593496 -106.74477)
		(property "Reference" "R3730"
			(at 0 0 0)
			(layer "F.SilkS")
			(hide yes)
			(effects
				(font
					(size 1.27 1.27)
				)
			)
		)
		(property "Value" ""
			(at 0 0 0)
			(layer "F.Fab")
			(effects
				(font
					(size 1.27 1.27)
				)
			)
		)
		(duplicate_pad_numbers_are_jumpers no)
		(fp_line
			(start -0.7874 -0.4064)
			(end 0.7874 -0.4064)
			(stroke
				(width 0.1524)
				(type default)
			)
			(layer "F.SilkS")
		)
		(fp_line
			(start -0.7874 0.4064)
			(end -0.7874 -0.4064)
			(stroke
				(width 0.1524)
				(type default)
			)
			(layer "F.SilkS")
		)
		(fp_line
			(start 0.7874 -0.4064)
			(end 0.7874 0.4064)
			(stroke
				(width 0.1524)
				(type default)
			)
			(layer "F.SilkS")
		)
		(fp_line
			(start 0.7874 0.4064)
			(end -0.7874 0.4064)
			(stroke
				(width 0.1524)
				(type default)
			)
			(layer "F.SilkS")
		)
		(fp_line
			(start -0.67945 -0.305054)
			(end -0.12065 -0.305054)
			(stroke
				(width 0.1)
				(type default)
			)
			(layer "F.Fab")
		)
		(fp_line
			(start -0.67945 0.3048)
			(end -0.67945 -0.305054)
			(stroke
				(width 0.1)
				(type default)
			)
			(layer "F.Fab")
		)
		(fp_line
			(start -0.12065 -0.305054)
			(end -0.12065 -0.2794)
			(stroke
				(width 0.1)
				(type default)
			)
			(layer "F.Fab")
		)
		(fp_line
			(start -0.12065 -0.2794)
			(end 0.12065 -0.2794)
			(stroke
				(width 0.1)
				(type default)
			)
			(layer "F.Fab")
		)
		(fp_line
			(start -0.12065 0.2794)
			(end -0.12065 0.3048)
			(stroke
				(width 0.1)
				(type default)
			)
			(layer "F.Fab")
		)
		(fp_line
			(start -0.12065 0.3048)
			(end -0.67945 0.3048)
			(stroke
				(width 0.1)
				(type default)
			)
			(layer "F.Fab")
		)
		(fp_line
			(start 0.120396 0.2794)
			(end -0.12065 0.2794)
			(stroke
				(width 0.1)
				(type default)
			)
			(layer "F.Fab")
		)
		(fp_line
			(start 0.120396 0.3048)
			(end 0.120396 0.2794)
			(stroke
				(width 0.1)
				(type default)
			)
			(layer "F.Fab")
		)
		(fp_line
			(start 0.12065 -0.3048)
			(end 0.67945 -0.3048)
			(stroke
				(width 0.1)
				(type default)
			)
			(layer "F.Fab")
		)
		(fp_line
			(start 0.12065 -0.2794)
			(end 0.12065 -0.3048)
			(stroke
				(width 0.1)
				(type default)
			)
			(layer "F.Fab")
		)
		(fp_line
			(start 0.67945 -0.3048)
			(end 0.67945 0.3048)
			(stroke
				(width 0.1)
				(type default)
			)
			(layer "F.Fab")
		)
		(fp_line
			(start 0.67945 0.3048)
			(end 0.120396 0.3048)
			(stroke
				(width 0.1)
				(type default)
			)
			(layer "F.Fab")
		)
		(pad "1" smd circle
			(at -0.40005 0)
			(size 0 0)
			(layers "F.Cu" "F.Mask" "F.Paste")
			(net "P3V3_AUX")
		)
		(pad "2" smd circle
			(at 0.40005 0)
			(size 0 0)
			(layers "F.Cu" "F.Mask" "F.Paste")
			(net "SMB_LM75_2_3V3AUX_SDA")
		)
	)
)
